FILE_TYPE = CONNECTIVITY;
{Allegro Design Entry HDL 17.2-2016 S081 (4005846) 1/11/2022}
"PAGE_NUMBER" = 196;
0"NC";
1"CLK_100M_GPU_2_DP"CDS_PHYS_NET_NAME"CLK_100M_GPU_2_DP";
2"CLK_100M_GPU_1_DP"CDS_PHYS_NET_NAME"CLK_100M_GPU_1_DP";
3"CLK_100M_GPU_1_DN"CDS_PHYS_NET_NAME"CLK_100M_GPU_1_DN";
4"CLK_100M_GPU_2_DN"CDS_PHYS_NET_NAME"CLK_100M_GPU_2_DN";
5"CLK_100M_SWB_DN"CDS_PHYS_NET_NAME"CLK_100M_SWB_DN";
6"CLK_100M_SWB_DP"CDS_PHYS_NET_NAME"CLK_100M_SWB_DP";
7"CLK_100M_OCP_V3_2_B_DN"CDS_PHYS_NET_NAME"CLK_100M_OCP_V3_2_B_DN";
8"CLK_100M_OCP_V3_2_A_DP"CDS_PHYS_NET_NAME"CLK_100M_OCP_V3_2_A_DP";
9"CLK_100M_OCP_V3_2_B_DP"CDS_PHYS_NET_NAME"CLK_100M_OCP_V3_2_B_DP";
10"CLK_100M_OCP_V3_2_A_DN"CDS_PHYS_NET_NAME"CLK_100M_OCP_V3_2_A_DN";
11"CLK_100M_OCP_V3_2_C_DP"CDS_PHYS_NET_NAME"CLK_100M_OCP_V3_2_C_DP";
12"CLK_100M_OCP_V3_2_C_DN"CDS_PHYS_NET_NAME"CLK_100M_OCP_V3_2_C_DN";
13"CLK_100M_OCP_V3_2_D_DP"CDS_PHYS_NET_NAME"CLK_100M_OCP_V3_2_D_DP";
14"CLK_100M_OCP_V3_2_D_DN"CDS_PHYS_NET_NAME"CLK_100M_OCP_V3_2_D_DN";
15"CLK_100M_GPU_1_R_DP"CDS_PHYS_NET_NAME"CLK_100M_GPU_1_R_DP";
16"CLK_100M_GPU_2_R_DP"CDS_PHYS_NET_NAME"CLK_100M_GPU_2_R_DP";
17"CLK_100M_GPU_1_R_DN"CDS_PHYS_NET_NAME"CLK_100M_GPU_1_R_DN";
18"CLK_100M_SWB_R_DN"CDS_PHYS_NET_NAME"CLK_100M_SWB_R_DN";
19"CLK_100M_SWB_R_DP"CDS_PHYS_NET_NAME"CLK_100M_SWB_R_DP";
20"CLK_100M_OCP_V3_2_D_R_DN"CDS_PHYS_NET_NAME"CLK_100M_OCP_V3_2_D_R_DN";
21"CLK_100M_OCP_V3_2_A_R_DP"CDS_PHYS_NET_NAME"CLK_100M_OCP_V3_2_A_R_DP";
22"CLK_100M_OCP_V3_2_D_R_DP"CDS_PHYS_NET_NAME"CLK_100M_OCP_V3_2_D_R_DP";
23"CLK_100M_OCP_V3_2_A_R_DN"CDS_PHYS_NET_NAME"CLK_100M_OCP_V3_2_A_R_DN";
24"CLK_100M_OCP_V3_2_C_R_DN"CDS_PHYS_NET_NAME"CLK_100M_OCP_V3_2_C_R_DN";
25"CLK_100M_OCP_V3_2_C_R_DP"CDS_PHYS_NET_NAME"CLK_100M_OCP_V3_2_C_R_DP";
26"CLK_100M_OCP_V3_2_B_R_DN"CDS_PHYS_NET_NAME"CLK_100M_OCP_V3_2_B_R_DN";
27"CLK_100M_OCP_V3_2_B_R_DP"CDS_PHYS_NET_NAME"CLK_100M_OCP_V3_2_B_R_DP";
28"CLK_100M_GPU_2_R_DN"CDS_PHYS_NET_NAME"CLK_100M_GPU_2_R_DN";
%"Q_RES"
"1","(-100,-7775)","0","pure_quanta","I10";
;
PART_NUMBER"CS02202FB02"
MATERIAL"CHIP"
VALUE"22"
TOLERANCE"1%"
WATTAGE"1/16W"
PACK_TYPE"0402LF"
$LOCATION"R3201"
CDS_LIB"pure_quanta"
CDS_LOCATION"R3201"
$SEC"1"
CDS_SEC"1";
"B"
$PN"2"14;
"A"
$PN"1"20;
%"Q_RES"
"1","(-100,-7625)","0","pure_quanta","I11";
;
PART_NUMBER"CS02202FB02"
MATERIAL"CHIP"
TOLERANCE"1%"
WATTAGE"1/16W"
PACK_TYPE"0402LF"
VALUE"22"
$LOCATION"R3200"
CDS_LIB"pure_quanta"
CDS_LOCATION"R3200"
$SEC"1"
CDS_SEC"1";
"B"
$PN"2"13;
"A"
$PN"1"22;
%"Q_RES"
"1","(-100,-7375)","0","pure_quanta","I12";
;
PART_NUMBER"CS02202FB02"
MATERIAL"CHIP"
VALUE"22"
TOLERANCE"1%"
WATTAGE"1/16W"
PACK_TYPE"0402LF"
$LOCATION"R3199"
CDS_LIB"pure_quanta"
CDS_LOCATION"R3199"
$SEC"1"
CDS_SEC"1";
"B"
$PN"2"12;
"A"
$PN"1"24;
%"Q_RES"
"1","(-100,-7225)","0","pure_quanta","I13";
;
PART_NUMBER"CS02202FB02"
PACK_TYPE"0402LF"
WATTAGE"1/16W"
MATERIAL"CHIP"
VALUE"22"
TOLERANCE"1%"
$LOCATION"R3198"
CDS_LIB"pure_quanta"
CDS_LOCATION"R3198"
$SEC"1"
CDS_SEC"1";
"B"
$PN"2"11;
"A"
$PN"1"25;
%"Q_RES"
"1","(-100,-6975)","0","pure_quanta","I14";
;
PART_NUMBER"CS02202FB02"
PACK_TYPE"0402LF"
TOLERANCE"1%"
VALUE"22"
MATERIAL"CHIP"
WATTAGE"1/16W"
$LOCATION"R3197"
CDS_LIB"pure_quanta"
CDS_LOCATION"R3197"
$SEC"1"
CDS_SEC"1";
"B"
$PN"2"7;
"A"
$PN"1"26;
%"Q_RES"
"1","(-100,-6825)","0","pure_quanta","I15";
;
PART_NUMBER"CS02202FB02"
PACK_TYPE"0402LF"
WATTAGE"1/16W"
VALUE"22"
TOLERANCE"1%"
MATERIAL"CHIP"
$LOCATION"R3196"
CDS_LIB"pure_quanta"
CDS_LOCATION"R3196"
$SEC"1"
CDS_SEC"1";
"B"
$PN"2"9;
"A"
$PN"1"27;
%"Q_RES"
"1","(-100,-6575)","0","pure_quanta","I16";
;
PART_NUMBER"CS02202FB02"
WATTAGE"1/16W"
PACK_TYPE"0402LF"
VALUE"22"
TOLERANCE"1%"
MATERIAL"CHIP"
$LOCATION"R3195"
CDS_LIB"pure_quanta"
CDS_LOCATION"R3195"
$SEC"1"
CDS_SEC"1";
"B"
$PN"2"10;
"A"
$PN"1"23;
%"Q_RES"
"1","(-100,-6425)","0","pure_quanta","I17";
;
PART_NUMBER"CS02202FB02"
WATTAGE"1/16W"
PACK_TYPE"0402LF"
TOLERANCE"1%"
MATERIAL"CHIP"
VALUE"22"
$LOCATION"R3194"
CDS_LIB"pure_quanta"
CDS_LOCATION"R3194"
$SEC"1"
CDS_SEC"1";
"B"
$PN"2"8;
"A"
$PN"1"21;
%"Q_RES"
"1","(-150,-3875)","0","pure_quanta","I18";
;
PART_NUMBER"CS00002JB13"
WATTAGE"1/16W"
PACK_TYPE"0402LF"
TOLERANCE"5%"
VALUE"0"
MATERIAL"CHIP"
$LOCATION"R3355"
CDS_LIB"pure_quanta"
CDS_LOCATION"R3355"
$SEC"1"
CDS_SEC"1";
"B"
$PN"2"4;
"A"
$PN"1"28;
%"Q_RES"
"1","(-150,-3725)","0","pure_quanta","I24";
;
PART_NUMBER"CS00002JB13"
PACK_TYPE"0402LF"
VALUE"0"
TOLERANCE"5%"
WATTAGE"1/16W"
MATERIAL"CHIP"
$LOCATION"R3354"
CDS_LIB"pure_quanta"
CDS_LOCATION"R3354"
$SEC"1"
CDS_SEC"1";
"B"
$PN"2"1;
"A"
$PN"1"16;
%"Q_RES"
"1","(-150,-3500)","0","pure_quanta","I25";
;
PART_NUMBER"CS00002JB13"
WATTAGE"1/16W"
MATERIAL"CHIP"
PACK_TYPE"0402LF"
VALUE"0"
TOLERANCE"5%"
$LOCATION"R3353"
CDS_LIB"pure_quanta"
CDS_LOCATION"R3353"
$SEC"1"
CDS_SEC"1";
"B"
$PN"2"3;
"A"
$PN"1"17;
%"Q_RES"
"1","(-150,-3350)","0","pure_quanta","I26";
;
PART_NUMBER"CS00002JB13"
TOLERANCE"5%"
PACK_TYPE"0402LF"
WATTAGE"1/16W"
VALUE"0"
MATERIAL"CHIP"
$LOCATION"R3352"
CDS_LIB"pure_quanta"
CDS_LOCATION"R3352"
$SEC"1"
CDS_SEC"1";
"B"
$PN"2"2;
"A"
$PN"1"15;
%"Q_RES"
"1","(-125,-2875)","0","pure_quanta","I27";
;
PART_NUMBER"CS00002JB13"
TOLERANCE"5%"
MATERIAL"CHIP"
PACK_TYPE"0402LF"
VALUE"0"
WATTAGE"1/16W"
$LOCATION"R2659"
CDS_LIB"pure_quanta"
CDS_LOCATION"R2659"
$SEC"1"
CDS_SEC"1";
"B"
$PN"2"6;
"A"
$PN"1"19;
%"Q_RES"
"1","(-125,-3025)","0","pure_quanta","I28";
;
PART_NUMBER"CS00002JB13"
PACK_TYPE"0402LF"
WATTAGE"1/16W"
MATERIAL"CHIP"
VALUE"0"
TOLERANCE"5%"
$LOCATION"R2660"
CDS_LIB"pure_quanta"
CDS_LOCATION"R2660"
$SEC"1"
CDS_SEC"1";
"B"
$PN"2"5;
"A"
$PN"1"18;
END.
